# T6G (Grand Teton) — schematic netlist excerpt (pin names and nets, part order shuffled) for the footprints in the layout excerpt that follows; sources: Cadence DE-HDL packaged netlist, KiCad conversion of 04192023_DAF0TMB3IC0_F0TG_MB_C_brd_V02_OCP.brd

C2255  Q_CAP  22UF 4V 20% X6S  pkg C0402  page 69 : A = PVDDCR_CPU1_P0 ; B = GND
C6541  Q_CAP_DIFFBUS  DIFF BUS_0.22UF 6.3V 20% X6S  pkg C0201  page 286 : \1\ = P5E_CPU0_P1_TX_BUF_C_DP<4> ; \2\ = P5E_CPU0_P1_TX_BUF_DP<4>
C97  Q_CAP  0.1UF 25V 10% X7R  pkg 0402  page 233 : A = VFG_3P3A_CLK_GEN ; B = GND

(kicad_pcb
	(version 20260206)
	(generator "pcbnew")
	(generator_version "10.0")
	(general
		(thickness 1.6)
		(legacy_teardrops no)
	)
	(paper "A4")
	(title_block
		(title "04192023_DAF0TMB3IC0_F0TG_MB_C_brd_V02_OCP.brd")
		(comment 1 "Grand Teton / footprints 7269-7271 of 8354")
	)
	(layers
		(0 "F.Cu" signal "TOP")
		(4 "In1.Cu" signal "GND")
		(6 "In2.Cu" signal "IN1")
		(8 "In3.Cu" signal "GND1")
		(10 "In4.Cu" signal "IN2")
		(12 "In5.Cu" signal "GND2")
		(14 "In6.Cu" signal "IN3")
		(16 "In7.Cu" signal "GND3")
		(18 "In8.Cu" signal "VCC")
		(20 "In9.Cu" signal "VCC1")
		(22 "In10.Cu" signal "GND4")
		(24 "In11.Cu" signal "IN4")
		(26 "In12.Cu" signal "GND5")
		(28 "In13.Cu" signal "IN5")
		(30 "In14.Cu" signal "GND6")
		(32 "In15.Cu" signal "IN6")
		(34 "In16.Cu" signal "GND7")
		(2 "B.Cu" signal "BOTTOM")
		(9 "F.Adhes" user "F.Adhesive")
		(11 "B.Adhes" user "B.Adhesive")
		(13 "F.Paste" user "Package Geometry/Pastemask Top")
		(15 "B.Paste" user "Package Geometry/Pastemask Bottom")
		(5 "F.SilkS" user "Ref Des/Silkscreen Top")
		(7 "B.SilkS" user "Ref Des/Silkscreen Bottom")
		(1 "F.Mask" user "Board Geometry/Soldermask Top")
		(3 "B.Mask" user "Board Geometry/Soldermask Bottom")
		(17 "Dwgs.User" user "User.Drawings")
		(19 "Cmts.User" user "User.Comments")
		(21 "Eco1.User" user "User.Eco1")
		(23 "Eco2.User" user "User.Eco2")
		(25 "Edge.Cuts" user "Board Geometry/Outline")
		(27 "Margin" user)
		(31 "F.CrtYd" user "Package Geometry/Place Bound Top")
		(29 "B.CrtYd" user "Package Geometry/Place Bound Bottom")
		(35 "F.Fab" user "Ref Des/Assembly Top")
		(33 "B.Fab" user "Ref Des/Assembly Bottom")
	)
	(footprint ""
		(layer "B.Cu")
		(at 15.042388 -134.16407)
		(property "Reference" "C97"
			(at 0 0 0)
			(layer "B.SilkS")
			(hide yes)
			(effects
				(font
					(size 1.27 1.27)
				)
				(justify mirror)
			)
		)
		(property "Value" ""
			(at 0 0 0)
			(layer "B.Fab")
			(effects
				(font
					(size 1.27 1.27)
				)
				(justify mirror)
			)
		)
		(duplicate_pad_numbers_are_jumpers no)
		(fp_line
			(start -0.7874 -0.4064)
			(end -0.7874 0.4064)
			(stroke
				(width 0.1524)
				(type default)
			)
			(layer "B.SilkS")
		)
		(fp_line
			(start -0.7874 0.4064)
			(end 0.7874 0.4064)
			(stroke
				(width 0.1524)
				(type default)
			)
			(layer "B.SilkS")
		)
		(fp_line
			(start 0.7874 -0.4064)
			(end -0.7874 -0.4064)
			(stroke
				(width 0.1524)
				(type default)
			)
			(layer "B.SilkS")
		)
		(fp_line
			(start 0.7874 0.4064)
			(end 0.7874 -0.4064)
			(stroke
				(width 0.1524)
				(type default)
			)
			(layer "B.SilkS")
		)
		(fp_line
			(start -0.67945 -0.3048)
			(end -0.67945 0.3048)
			(stroke
				(width 0.1)
				(type default)
			)
			(layer "B.Fab")
		)
		(fp_line
			(start -0.67945 0.3048)
			(end -0.120396 0.3048)
			(stroke
				(width 0.1)
				(type default)
			)
			(layer "B.Fab")
		)
		(fp_line
			(start -0.12065 -0.3048)
			(end -0.67945 -0.3048)
			(stroke
				(width 0.1)
				(type default)
			)
			(layer "B.Fab")
		)
		(fp_line
			(start -0.12065 -0.2794)
			(end -0.12065 -0.3048)
			(stroke
				(width 0.1)
				(type default)
			)
			(layer "B.Fab")
		)
		(fp_line
			(start -0.120396 0.2794)
			(end 0.12065 0.2794)
			(stroke
				(width 0.1)
				(type default)
			)
			(layer "B.Fab")
		)
		(fp_line
			(start -0.120396 0.3048)
			(end -0.120396 0.2794)
			(stroke
				(width 0.1)
				(type default)
			)
			(layer "B.Fab")
		)
		(fp_line
			(start 0.12065 -0.305054)
			(end 0.12065 -0.2794)
			(stroke
				(width 0.1)
				(type default)
			)
			(layer "B.Fab")
		)
		(fp_line
			(start 0.12065 -0.2794)
			(end -0.12065 -0.2794)
			(stroke
				(width 0.1)
				(type default)
			)
			(layer "B.Fab")
		)
		(fp_line
			(start 0.12065 0.2794)
			(end 0.12065 0.3048)
			(stroke
				(width 0.1)
				(type default)
			)
			(layer "B.Fab")
		)
		(fp_line
			(start 0.12065 0.3048)
			(end 0.67945 0.3048)
			(stroke
				(width 0.1)
				(type default)
			)
			(layer "B.Fab")
		)
		(fp_line
			(start 0.67945 -0.305054)
			(end 0.12065 -0.305054)
			(stroke
				(width 0.1)
				(type default)
			)
			(layer "B.Fab")
		)
		(fp_line
			(start 0.67945 0.3048)
			(end 0.67945 -0.305054)
			(stroke
				(width 0.1)
				(type default)
			)
			(layer "B.Fab")
		)
		(pad "1" smd circle
			(at 0.40005 0 180)
			(size 0 0)
			(layers "B.Cu" "B.Mask" "B.Paste")
			(net "VFG_3P3A_CLK_GEN")
		)
		(pad "2" smd circle
			(at -0.40005 0 180)
			(size 0 0)
			(layers "B.Cu" "B.Mask" "B.Paste")
			(net "GND")
		)
	)
	(footprint ""
		(layer "B.Cu")
		(at 365.773208 -267.52931)
		(property "Reference" "C2255"
			(at 0 0 0)
			(layer "B.SilkS")
			(hide yes)
			(effects
				(font
					(size 1.27 1.27)
				)
				(justify mirror)
			)
		)
		(property "Value" ""
			(at 0 0 0)
			(layer "B.Fab")
			(effects
				(font
					(size 1.27 1.27)
				)
				(justify mirror)
			)
		)
		(duplicate_pad_numbers_are_jumpers no)
		(fp_line
			(start -0.7874 -0.4064)
			(end -0.7874 0.4064)
			(stroke
				(width 0.1524)
				(type default)
			)
			(layer "B.SilkS")
		)
		(fp_line
			(start -0.7874 0.4064)
			(end 0.7874 0.4064)
			(stroke
				(width 0.1524)
				(type default)
			)
			(layer "B.SilkS")
		)
		(fp_line
			(start 0.7874 -0.4064)
			(end -0.7874 -0.4064)
			(stroke
				(width 0.1524)
				(type default)
			)
			(layer "B.SilkS")
		)
		(fp_line
			(start 0.7874 0.4064)
			(end 0.7874 -0.4064)
			(stroke
				(width 0.1524)
				(type default)
			)
			(layer "B.SilkS")
		)
		(fp_line
			(start -0.67945 -0.3048)
			(end -0.67945 0.3048)
			(stroke
				(width 0.1)
				(type default)
			)
			(layer "B.Fab")
		)
		(fp_line
			(start -0.67945 0.3048)
			(end -0.120396 0.3048)
			(stroke
				(width 0.1)
				(type default)
			)
			(layer "B.Fab")
		)
		(fp_line
			(start -0.12065 -0.3048)
			(end -0.67945 -0.3048)
			(stroke
				(width 0.1)
				(type default)
			)
			(layer "B.Fab")
		)
		(fp_line
			(start -0.12065 -0.2794)
			(end -0.12065 -0.3048)
			(stroke
				(width 0.1)
				(type default)
			)
			(layer "B.Fab")
		)
		(fp_line
			(start -0.120396 0.2794)
			(end 0.12065 0.2794)
			(stroke
				(width 0.1)
				(type default)
			)
			(layer "B.Fab")
		)
		(fp_line
			(start -0.120396 0.3048)
			(end -0.120396 0.2794)
			(stroke
				(width 0.1)
				(type default)
			)
			(layer "B.Fab")
		)
		(fp_line
			(start 0.12065 -0.305054)
			(end 0.12065 -0.2794)
			(stroke
				(width 0.1)
				(type default)
			)
			(layer "B.Fab")
		)
		(fp_line
			(start 0.12065 -0.2794)
			(end -0.12065 -0.2794)
			(stroke
				(width 0.1)
				(type default)
			)
			(layer "B.Fab")
		)
		(fp_line
			(start 0.12065 0.2794)
			(end 0.12065 0.3048)
			(stroke
				(width 0.1)
				(type default)
			)
			(layer "B.Fab")
		)
		(fp_line
			(start 0.12065 0.3048)
			(end 0.67945 0.3048)
			(stroke
				(width 0.1)
				(type default)
			)
			(layer "B.Fab")
		)
		(fp_line
			(start 0.67945 -0.305054)
			(end 0.12065 -0.305054)
			(stroke
				(width 0.1)
				(type default)
			)
			(layer "B.Fab")
		)
		(fp_line
			(start 0.67945 0.3048)
			(end 0.67945 -0.305054)
			(stroke
				(width 0.1)
				(type default)
			)
			(layer "B.Fab")
		)
		(pad "1" smd circle
			(at 0.40005 0 180)
			(size 0 0)
			(layers "B.Cu" "B.Mask" "B.Paste")
			(net "PVDDCR_CPU1_P0")
		)
		(pad "2" smd circle
			(at -0.40005 0 180)
			(size 0 0)
			(layers "B.Cu" "B.Mask" "B.Paste")
			(net "GND")
		)
	)
	(footprint ""
		(layer "B.Cu")
		(at 318.467486 -416.899344 90)
		(property "Reference" "C6541"
			(at 0 0 90)
			(layer "B.SilkS")
			(hide yes)
			(effects
				(font
					(size 1.27 1.27)
				)
				(justify mirror)
			)
		)
		(property "Value" ""
			(at 0 0 90)
			(layer "B.Fab")
			(effects
				(font
					(size 1.27 1.27)
				)
				(justify mirror)
			)
		)
		(duplicate_pad_numbers_are_jumpers no)
		(fp_line
			(start 0.299974 -0.150114)
			(end -0.299974 -0.150114)
			(stroke
				(width 0.1)
				(type default)
			)
			(layer "B.Fab")
		)
		(fp_line
			(start -0.299974 -0.150114)
			(end -0.299974 0.150114)
			(stroke
				(width 0.1)
				(type default)
			)
			(layer "B.Fab")
		)
		(fp_line
			(start 0.299974 0.150114)
			(end 0.299974 -0.150114)
			(stroke
				(width 0.1)
				(type default)
			)
			(layer "B.Fab")
		)
		(fp_line
			(start -0.299974 0.150114)
			(end 0.299974 0.150114)
			(stroke
				(width 0.1)
				(type default)
			)
			(layer "B.Fab")
		)
		(pad "1" smd rect
			(at 0.2667 0 270)
			(size 0.3048 0.381)
			(layers "B.Cu" "B.Mask" "B.Paste")
			(net "P5E_CPU0_P1_TX_BUF_C_DP<4>")
		)
		(pad "2" smd rect
			(at -0.2667 0 270)
			(size 0.3048 0.381)
			(layers "B.Cu" "B.Mask" "B.Paste")
			(net "P5E_CPU0_P1_TX_BUF_DP<4>")
		)
	)
)
